# BASEBOARD_FAB2 (Tioga Pass) — schematic netlist excerpt (pin names and nets, part order shuffled) for the footprints in the layout excerpt that follows; sources: Cadence DE-HDL packaged netlist, KiCad conversion of Wiwynn_Tioga_Pass_MB.brd

R3N30  RES  0.0 5% EMPTY  pkg 0402  page 152 : A = H_CPU0_MEMABC_MEMHOT_LVT3_N ; B = H_CPU0_MEMABC_MEMHOT_PCH_N
R1L18  RES  10.0 1% CHIP  pkg 0402  page 155 : A = LED_POSTCODE_5 ; B = LED_POSTCODE_5_R
C8T11  CAP_A  47UF 4V 20% X5R  pkg 0603V  page 225 : A = PVDDQ_GHJ ; B = GND

(kicad_pcb
	(version 20260206)
	(generator "pcbnew")
	(generator_version "10.0")
	(general
		(thickness 1.6)
		(legacy_teardrops no)
	)
	(paper "A4")
	(title_block
		(title "Wiwynn_Tioga_Pass_MB.brd")
		(comment 1 "Tioga Pass / footprints 3231-3233 of 4770")
	)
	(layers
		(0 "F.Cu" signal "TOP")
		(4 "In1.Cu" signal "L2GND")
		(6 "In2.Cu" signal "L3")
		(8 "In3.Cu" signal "L4GND")
		(10 "In4.Cu" signal "L5")
		(12 "In5.Cu" signal "L6GND")
		(14 "In6.Cu" signal "L7VCC")
		(16 "In7.Cu" signal "L8VCC")
		(18 "In8.Cu" signal "L9GND")
		(20 "In9.Cu" signal "L10")
		(22 "In10.Cu" signal "L11GND")
		(24 "In11.Cu" signal "L12")
		(26 "In12.Cu" signal "L13GND")
		(2 "B.Cu" signal "BOTTOM")
		(9 "F.Adhes" user "F.Adhesive")
		(11 "B.Adhes" user "B.Adhesive")
		(13 "F.Paste" user "Package Geometry/Pastemask Top")
		(15 "B.Paste" user "Package Geometry/Pastemask Bottom")
		(5 "F.SilkS" user "Ref Des/Silkscreen Top")
		(7 "B.SilkS" user "Ref Des/Silkscreen Bottom")
		(1 "F.Mask" user "Board Geometry/Soldermask Top")
		(3 "B.Mask" user "Board Geometry/Soldermask Bottom")
		(17 "Dwgs.User" user "User.Drawings")
		(19 "Cmts.User" user "User.Comments")
		(21 "Eco1.User" user "User.Eco1")
		(23 "Eco2.User" user "User.Eco2")
		(25 "Edge.Cuts" user "Board Geometry/Outline")
		(27 "Margin" user)
		(31 "F.CrtYd" user "Package Geometry/Place Bound Top")
		(29 "B.CrtYd" user "Package Geometry/Place Bound Bottom")
		(35 "F.Fab" user "Ref Des/Assembly Top")
		(33 "B.Fab" user "Ref Des/Assembly Bottom")
	)
	(footprint ""
		(layer "B.Cu")
		(at 93.241368 -17.6276 -90)
		(property "Reference" "C8T11"
			(at 0 0 90)
			(layer "B.SilkS")
			(hide yes)
			(effects
				(font
					(size 1.27 1.27)
				)
				(justify mirror)
			)
		)
		(property "Value" ""
			(at 0 0 90)
			(layer "B.Fab")
			(effects
				(font
					(size 1.27 1.27)
				)
				(justify mirror)
			)
		)
		(duplicate_pad_numbers_are_jumpers no)
		(fp_rect
			(start 0.500126 1.598422)
			(end -0.500126 -0.201422)
			(stroke
				(width 0)
				(type default)
			)
			(fill no)
			(layer "B.CrtYd")
		)
		(fp_line
			(start -0.500126 1.598422)
			(end 0.500126 1.598422)
			(stroke
				(width 0.1)
				(type default)
			)
			(layer "B.Fab")
		)
		(fp_line
			(start 0.500126 1.598422)
			(end 0.500126 -0.201422)
			(stroke
				(width 0.1)
				(type default)
			)
			(layer "B.Fab")
		)
		(fp_line
			(start -0.500126 -0.201422)
			(end -0.500126 1.598422)
			(stroke
				(width 0.1)
				(type default)
			)
			(layer "B.Fab")
		)
		(fp_line
			(start 0.500126 -0.201422)
			(end -0.500126 -0.201422)
			(stroke
				(width 0.1)
				(type default)
			)
			(layer "B.Fab")
		)
		(pad "1" smd rect
			(at 0 0 180)
			(size 0.889 0.9906)
			(layers "B.Cu" "B.Mask" "B.Paste")
			(net "PVDDQ_GHJ")
		)
		(pad "2" smd rect
			(at 0 1.397 180)
			(size 0.889 0.9906)
			(layers "B.Cu" "B.Mask" "B.Paste")
			(net "GND")
		)
		(zone
			(layer "B.Cu")
			(hatch none 0.5)
			(connect_pads
				(clearance 0)
			)
			(min_thickness 0.25)
			(keepout
				(tracks allowed)
				(vias not_allowed)
				(pads allowed)
				(copperpour not_allowed)
				(footprints allowed)
			)
			(placement
				(enabled no)
				(sheetname "")
			)
			(fill
				(thermal_gap 0.5)
				(thermal_bridge_width 0.5)
				(island_removal_mode 0)
			)
			(polygon
				(pts
					(xy 92.288868 -17.1323) (xy 92.796868 -17.1323) (xy 92.796868 -18.1229) (xy 92.288868 -18.1229)
				)
			)
		)
		(zone
			(layer "B.Cu")
			(hatch none 0.5)
			(connect_pads
				(clearance 0)
			)
			(min_thickness 0.25)
			(keepout
				(tracks not_allowed)
				(vias allowed)
				(pads allowed)
				(copperpour not_allowed)
				(footprints allowed)
			)
			(placement
				(enabled no)
				(sheetname "")
			)
			(fill
				(thermal_gap 0.5)
				(thermal_bridge_width 0.5)
				(island_removal_mode 0)
			)
			(polygon
				(pts
					(xy 92.288868 -17.1323) (xy 92.796868 -17.1323) (xy 92.796868 -18.1229) (xy 92.288868 -18.1229)
				)
			)
		)
	)
	(footprint ""
		(layer "B.Cu")
		(at 489.65739 -146.177 90)
		(property "Reference" "R1L18"
			(at 0 0 90)
			(layer "B.SilkS")
			(hide yes)
			(effects
				(font
					(size 1.27 1.27)
				)
				(justify mirror)
			)
		)
		(property "Value" ""
			(at 0 0 90)
			(layer "B.Fab")
			(effects
				(font
					(size 1.27 1.27)
				)
				(justify mirror)
			)
		)
		(duplicate_pad_numbers_are_jumpers no)
		(fp_poly
			(pts
				(xy 0.2794 -0.1016) (xy -0.2794 -0.1016) (xy -0.2794 0.9906) (xy 0.2794 0.9906)
			)
			(stroke
				(width 0)
				(type default)
			)
			(fill no)
			(layer "B.CrtYd")
		)
		(fp_line
			(start 0.2794 -0.1016)
			(end 0.2794 0.9906)
			(stroke
				(width 0.1)
				(type default)
			)
			(layer "B.Fab")
		)
		(fp_line
			(start -0.2794 -0.1016)
			(end 0.2794 -0.1016)
			(stroke
				(width 0.1)
				(type default)
			)
			(layer "B.Fab")
		)
		(fp_line
			(start 0.2794 0.9906)
			(end -0.2794 0.9906)
			(stroke
				(width 0.1)
				(type default)
			)
			(layer "B.Fab")
		)
		(fp_line
			(start -0.2794 0.9906)
			(end -0.2794 -0.1016)
			(stroke
				(width 0.1)
				(type default)
			)
			(layer "B.Fab")
		)
		(pad "1" smd rect
			(at 0 0 270)
			(size 0.508 0.508)
			(layers "B.Cu" "B.Mask" "B.Paste")
			(net "LED_POSTCODE_5")
		)
		(pad "2" smd rect
			(at 0 0.889 270)
			(size 0.508 0.508)
			(layers "B.Cu" "B.Mask" "B.Paste")
			(net "LED_POSTCODE_5_R")
		)
		(zone
			(layer "B.Cu")
			(hatch none 0.5)
			(connect_pads
				(clearance 0)
			)
			(min_thickness 0.25)
			(keepout
				(tracks allowed)
				(vias not_allowed)
				(pads allowed)
				(copperpour not_allowed)
				(footprints allowed)
			)
			(placement
				(enabled no)
				(sheetname "")
			)
			(fill
				(thermal_gap 0.5)
				(thermal_bridge_width 0.5)
				(island_removal_mode 0)
			)
			(polygon
				(pts
					(xy 489.91139 -146.431) (xy 489.91139 -145.923) (xy 490.29239 -145.923) (xy 490.29239 -146.431)
				)
			)
		)
		(zone
			(layer "B.Cu")
			(hatch none 0.5)
			(connect_pads
				(clearance 0)
			)
			(min_thickness 0.25)
			(keepout
				(tracks not_allowed)
				(vias allowed)
				(pads allowed)
				(copperpour not_allowed)
				(footprints allowed)
			)
			(placement
				(enabled no)
				(sheetname "")
			)
			(fill
				(thermal_gap 0.5)
				(thermal_bridge_width 0.5)
				(island_removal_mode 0)
			)
			(polygon
				(pts
					(xy 490.29239 -146.431) (xy 490.29239 -145.923) (xy 489.91139 -145.923) (xy 489.91139 -146.431)
				)
			)
		)
	)
	(footprint ""
		(layer "B.Cu")
		(at 381.7239 -84.6836 180)
		(property "Reference" "R3N30"
			(at 0.8382 -0.67818 180)
			(unlocked yes)
			(layer "B.SilkS")
			(effects
				(font
					(size 0.4064 0.254)
					(thickness 0.1524)
				)
				(justify left mirror)
			)
		)
		(property "Value" ""
			(at 0 0 0)
			(layer "B.Fab")
			(effects
				(font
					(size 1.27 1.27)
				)
				(justify mirror)
			)
		)
		(duplicate_pad_numbers_are_jumpers no)
		(fp_poly
			(pts
				(xy 0.2794 -0.1016) (xy -0.2794 -0.1016) (xy -0.2794 0.9906) (xy 0.2794 0.9906)
			)
			(stroke
				(width 0)
				(type default)
			)
			(fill no)
			(layer "B.CrtYd")
		)
		(fp_line
			(start 0.2794 0.9906)
			(end -0.2794 0.9906)
			(stroke
				(width 0.1)
				(type default)
			)
			(layer "B.Fab")
		)
		(fp_line
			(start 0.2794 -0.1016)
			(end 0.2794 0.9906)
			(stroke
				(width 0.1)
				(type default)
			)
			(layer "B.Fab")
		)
		(fp_line
			(start -0.2794 0.9906)
			(end -0.2794 -0.1016)
			(stroke
				(width 0.1)
				(type default)
			)
			(layer "B.Fab")
		)
		(fp_line
			(start -0.2794 -0.1016)
			(end 0.2794 -0.1016)
			(stroke
				(width 0.1)
				(type default)
			)
			(layer "B.Fab")
		)
		(pad "1" smd rect
			(at 0 0)
			(size 0.508 0.508)
			(layers "B.Cu" "B.Mask" "B.Paste")
			(net "H_CPU0_MEMABC_MEMHOT_LVT3_N")
		)
		(pad "2" smd rect
			(at 0 0.889)
			(size 0.508 0.508)
			(layers "B.Cu" "B.Mask" "B.Paste")
			(net "H_CPU0_MEMABC_MEMHOT_PCH_N")
		)
		(zone
			(layer "B.Cu")
			(hatch none 0.5)
			(connect_pads
				(clearance 0)
			)
			(min_thickness 0.25)
			(keepout
				(tracks not_allowed)
				(vias allowed)
				(pads allowed)
				(copperpour not_allowed)
				(footprints allowed)
			)
			(placement
				(enabled no)
				(sheetname "")
			)
			(fill
				(thermal_gap 0.5)
				(thermal_bridge_width 0.5)
				(island_removal_mode 0)
			)
			(polygon
				(pts
					(xy 381.4699 -85.3186) (xy 381.9779 -85.3186) (xy 381.9779 -84.9376) (xy 381.4699 -84.9376)
				)
			)
		)
		(zone
			(layer "B.Cu")
			(hatch none 0.5)
			(connect_pads
				(clearance 0)
			)
			(min_thickness 0.25)
			(keepout
				(tracks allowed)
				(vias not_allowed)
				(pads allowed)
				(copperpour not_allowed)
				(footprints allowed)
			)
			(placement
				(enabled no)
				(sheetname "")
			)
			(fill
				(thermal_gap 0.5)
				(thermal_bridge_width 0.5)
				(island_removal_mode 0)
			)
			(polygon
				(pts
					(xy 381.4699 -84.9376) (xy 381.9779 -84.9376) (xy 381.9779 -85.3186) (xy 381.4699 -85.3186)
				)
			)
		)
	)
)
